# T6G (Grand Teton) — schematic netlist excerpt (pin names and nets, part order shuffled) for the footprints in the layout excerpt that follows; sources: Cadence DE-HDL packaged netlist, KiCad conversion of 04192023_DAF0TMB3IC0_F0TG_MB_C_brd_V02_OCP.brd

PL48  Q_INDUCTOR4P_14  150NH IND  pkg L_TLM117513Q-151QL_11X7-5XA  page 222
  \1\  = SW_PVDDIO_P1_SW2
  \2\  = IND_PVDDIO_P1_CPL3
  \3\  = IND_PVDDIO_P1_CPL2
  \4\  = PVDDIO_P1

R271  Q_RES  0 5% CHIP  pkg 0402LF  page 82 : A = FM_PRSNT_CPU1_R_N ; B = FM_PRSNT_CPU1_N

(kicad_pcb
	(version 20260206)
	(generator "pcbnew")
	(generator_version "10.0")
	(general
		(thickness 1.6)
		(legacy_teardrops no)
	)
	(paper "A4")
	(title_block
		(title "04192023_DAF0TMB3IC0_F0TG_MB_C_brd_V02_OCP.brd")
		(comment 1 "Grand Teton / footprints 1422-1423 of 8354")
	)
	(layers
		(0 "F.Cu" signal "TOP")
		(4 "In1.Cu" signal "GND")
		(6 "In2.Cu" signal "IN1")
		(8 "In3.Cu" signal "GND1")
		(10 "In4.Cu" signal "IN2")
		(12 "In5.Cu" signal "GND2")
		(14 "In6.Cu" signal "IN3")
		(16 "In7.Cu" signal "GND3")
		(18 "In8.Cu" signal "VCC")
		(20 "In9.Cu" signal "VCC1")
		(22 "In10.Cu" signal "GND4")
		(24 "In11.Cu" signal "IN4")
		(26 "In12.Cu" signal "GND5")
		(28 "In13.Cu" signal "IN5")
		(30 "In14.Cu" signal "GND6")
		(32 "In15.Cu" signal "IN6")
		(34 "In16.Cu" signal "GND7")
		(2 "B.Cu" signal "BOTTOM")
		(9 "F.Adhes" user "F.Adhesive")
		(11 "B.Adhes" user "B.Adhesive")
		(13 "F.Paste" user "Package Geometry/Pastemask Top")
		(15 "B.Paste" user "Package Geometry/Pastemask Bottom")
		(5 "F.SilkS" user "Ref Des/Silkscreen Top")
		(7 "B.SilkS" user "Ref Des/Silkscreen Bottom")
		(1 "F.Mask" user "Board Geometry/Soldermask Top")
		(3 "B.Mask" user "Board Geometry/Soldermask Bottom")
		(17 "Dwgs.User" user "User.Drawings")
		(19 "Cmts.User" user "User.Comments")
		(21 "Eco1.User" user "User.Eco1")
		(23 "Eco2.User" user "User.Eco2")
		(25 "Edge.Cuts" user "Board Geometry/Outline")
		(27 "Margin" user)
		(31 "F.CrtYd" user "Package Geometry/Place Bound Top")
		(29 "B.CrtYd" user "Package Geometry/Place Bound Bottom")
		(35 "F.Fab" user "Ref Des/Assembly Top")
		(33 "B.Fab" user "Ref Des/Assembly Bottom")
	)
	(footprint ""
		(layer "F.Cu")
		(at 193.929 -96.103948 -90)
		(property "Reference" "R271"
			(at 0 0 270)
			(layer "F.SilkS")
			(hide yes)
			(effects
				(font
					(size 1.27 1.27)
				)
			)
		)
		(property "Value" ""
			(at 0 0 270)
			(layer "F.Fab")
			(effects
				(font
					(size 1.27 1.27)
				)
			)
		)
		(duplicate_pad_numbers_are_jumpers no)
		(fp_line
			(start -0.7874 0.4064)
			(end -0.7874 -0.4064)
			(stroke
				(width 0.1524)
				(type default)
			)
			(layer "F.SilkS")
		)
		(fp_line
			(start 0.7874 0.4064)
			(end -0.7874 0.4064)
			(stroke
				(width 0.1524)
				(type default)
			)
			(layer "F.SilkS")
		)
		(fp_line
			(start -0.7874 -0.4064)
			(end 0.7874 -0.4064)
			(stroke
				(width 0.1524)
				(type default)
			)
			(layer "F.SilkS")
		)
		(fp_line
			(start 0.7874 -0.4064)
			(end 0.7874 0.4064)
			(stroke
				(width 0.1524)
				(type default)
			)
			(layer "F.SilkS")
		)
		(fp_line
			(start -0.67945 0.3048)
			(end -0.67945 -0.305054)
			(stroke
				(width 0.1)
				(type default)
			)
			(layer "F.Fab")
		)
		(fp_line
			(start -0.12065 0.3048)
			(end -0.67945 0.3048)
			(stroke
				(width 0.1)
				(type default)
			)
			(layer "F.Fab")
		)
		(fp_line
			(start 0.120396 0.3048)
			(end 0.120396 0.2794)
			(stroke
				(width 0.1)
				(type default)
			)
			(layer "F.Fab")
		)
		(fp_line
			(start 0.67945 0.3048)
			(end 0.120396 0.3048)
			(stroke
				(width 0.1)
				(type default)
			)
			(layer "F.Fab")
		)
		(fp_line
			(start -0.12065 0.2794)
			(end -0.12065 0.3048)
			(stroke
				(width 0.1)
				(type default)
			)
			(layer "F.Fab")
		)
		(fp_line
			(start 0.120396 0.2794)
			(end -0.12065 0.2794)
			(stroke
				(width 0.1)
				(type default)
			)
			(layer "F.Fab")
		)
		(fp_line
			(start -0.12065 -0.2794)
			(end 0.12065 -0.2794)
			(stroke
				(width 0.1)
				(type default)
			)
			(layer "F.Fab")
		)
		(fp_line
			(start 0.12065 -0.2794)
			(end 0.12065 -0.3048)
			(stroke
				(width 0.1)
				(type default)
			)
			(layer "F.Fab")
		)
		(fp_line
			(start 0.12065 -0.3048)
			(end 0.67945 -0.3048)
			(stroke
				(width 0.1)
				(type default)
			)
			(layer "F.Fab")
		)
		(fp_line
			(start 0.67945 -0.3048)
			(end 0.67945 0.3048)
			(stroke
				(width 0.1)
				(type default)
			)
			(layer "F.Fab")
		)
		(fp_line
			(start -0.67945 -0.305054)
			(end -0.12065 -0.305054)
			(stroke
				(width 0.1)
				(type default)
			)
			(layer "F.Fab")
		)
		(fp_line
			(start -0.12065 -0.305054)
			(end -0.12065 -0.2794)
			(stroke
				(width 0.1)
				(type default)
			)
			(layer "F.Fab")
		)
		(pad "1" smd circle
			(at -0.40005 0 270)
			(size 0 0)
			(layers "F.Cu" "F.Mask" "F.Paste")
			(net "FM_PRSNT_CPU1_R_N")
		)
		(pad "2" smd circle
			(at 0.40005 0 270)
			(size 0 0)
			(layers "F.Cu" "F.Mask" "F.Paste")
			(net "FM_PRSNT_CPU1_N")
		)
	)
	(footprint ""
		(layer "F.Cu")
		(at 45.25391 -337.403948)
		(property "Reference" "PL48"
			(at -3.115056 -15.887446 0)
			(unlocked yes)
			(layer "F.SilkS")
			(effects
				(font
					(size 0.7874 0.5842)
					(thickness 0.1524)
				)
				(justify left)
			)
		)
		(property "Value" ""
			(at 0 0 0)
			(layer "F.Fab")
			(effects
				(font
					(size 1.27 1.27)
				)
			)
		)
		(duplicate_pad_numbers_are_jumpers no)
		(fp_line
			(start -3.750056 -5.500116)
			(end -2.393442 -5.500116)
			(stroke
				(width 0.1524)
				(type default)
			)
			(layer "F.SilkS")
		)
		(fp_line
			(start -3.750056 5.500116)
			(end -3.750056 -5.500116)
			(stroke
				(width 0.1524)
				(type default)
			)
			(layer "F.SilkS")
		)
		(fp_line
			(start -2.393442 5.500116)
			(end -3.750056 5.500116)
			(stroke
				(width 0.1524)
				(type default)
			)
			(layer "F.SilkS")
		)
		(fp_line
			(start 2.393442 5.500116)
			(end 3.750056 5.500116)
			(stroke
				(width 0.1524)
				(type default)
			)
			(layer "F.SilkS")
		)
		(fp_line
			(start 3.750056 -5.500116)
			(end 2.393442 -5.500116)
			(stroke
				(width 0.1524)
				(type default)
			)
			(layer "F.SilkS")
		)
		(fp_line
			(start 3.750056 5.500116)
			(end 3.750056 -5.500116)
			(stroke
				(width 0.1524)
				(type default)
			)
			(layer "F.SilkS")
		)
		(fp_poly
			(pts
				(xy -3.9116 -4.249928) (xy -4.35991 -4.0259) (xy -4.35991 -4.473956)
			)
			(stroke
				(width 0)
				(type default)
			)
			(fill yes)
			(layer "F.SilkS")
		)
		(fp_line
			(start -3.750056 -5.500116)
			(end -3.750056 5.500116)
			(stroke
				(width 0.1)
				(type default)
			)
			(layer "F.Fab")
		)
		(fp_line
			(start -3.750056 5.500116)
			(end 3.750056 5.500116)
			(stroke
				(width 0.1)
				(type default)
			)
			(layer "F.Fab")
		)
		(fp_line
			(start 3.750056 -5.500116)
			(end -3.750056 -5.500116)
			(stroke
				(width 0.1)
				(type default)
			)
			(layer "F.Fab")
		)
		(fp_line
			(start 3.750056 5.500116)
			(end 3.750056 -5.500116)
			(stroke
				(width 0.1)
				(type default)
			)
			(layer "F.Fab")
		)
		(fp_poly
			(pts
				(xy -4.9276 -4.757928) (xy -4.9276 -3.741928) (xy -3.9116 -4.249928)
			)
			(stroke
				(width 0)
				(type default)
			)
			(fill yes)
			(layer "F.Fab")
		)
		(pad "1" smd rect
			(at 0 -4.249928 270)
			(size 2.413 4.5212)
			(layers "F.Cu" "F.Mask" "F.Paste")
			(net "SW_PVDDIO_P1_SW2")
		)
		(pad "2" smd rect
			(at 0 -1.175004 270)
			(size 1.3716 4.5212)
			(layers "F.Cu" "F.Mask" "F.Paste")
			(net "IND_PVDDIO_P1_CPL3")
		)
		(pad "3" smd rect
			(at 0 1.175004 270)
			(size 1.3716 4.5212)
			(layers "F.Cu" "F.Mask" "F.Paste")
			(net "IND_PVDDIO_P1_CPL2")
		)
		(pad "4" smd rect
			(at 0 4.249928 270)
			(size 2.413 4.5212)
			(layers "F.Cu" "F.Mask" "F.Paste")
			(net "PVDDIO_P1")
		)
	)
)
